(kicad_pcb
	(version 20221018)
	(generator pcbnew)
	(general
    (thickness 1.7403)
  )
	(paper "A4")
	(title_block
    (title "Data Center RDIMM DDR4 Tester")
    (date "2024-09-30")
    (rev "1.2.4")
		(comment 9 "footprint 168 of 690 (U15), pads 90-179 of 676")
	)
	(layers
    (0 "F.Cu" signal)
    (1 "In1.Cu" power)
    (2 "In2.Cu" signal)
    (3 "In3.Cu" power)
    (4 "In4.Cu" power)
    (5 "In5.Cu" signal)
    (6 "In6.Cu" power)
    (7 "In7.Cu" signal)
    (8 "In8.Cu" power)
    (9 "In9.Cu" signal)
    (10 "In10.Cu" power)
    (31 "B.Cu" signal)
    (32 "B.Adhes" user "B.Adhesive")
    (33 "F.Adhes" user "F.Adhesive")
    (34 "B.Paste" user)
    (35 "F.Paste" user)
    (36 "B.SilkS" user "B.Silkscreen")
    (37 "F.SilkS" user "F.Silkscreen")
    (38 "B.Mask" user)
    (39 "F.Mask" user)
    (40 "Dwgs.User" user "User.Drawings")
    (41 "Cmts.User" user "User.Comments")
    (42 "Eco1.User" user "User.Eco1")
    (43 "Eco2.User" user "User.Eco2")
    (44 "Edge.Cuts" user)
    (45 "Margin" user)
    (46 "B.CrtYd" user "B.Courtyard")
    (47 "F.CrtYd" user "F.Courtyard")
    (48 "B.Fab" user)
    (49 "F.Fab" user)
  )
	(footprint "data-center-rdimm-ddr4-tester-footprints:BGA-676_27x27mm_Layout26x26_P1X1mm"
    (layer "F.Cu")
    (at 183.635 90.06 180)
    (descr "FPGA XC7K160TFBG676")
    (tags "FPGA XC7K160TFBG676")
    (property "Author" "Antmicro")
    (property "License" "Apache-2.0")
    (property "MPN" "XC7K160T-FFG676")
    (property "Manufacturer" "AMD-Xilinx")
    (property "Sheetfile" "config-spi.kicad_sch")
    (property "Sheetname" "Config SPI flash")
    (property "ki_description" "Kintex®-7 Field Programmable Gate Array (FPGA) IC 300 4976640 65600 676-BBGA, FCBGA")
    (property "ki_keywords" "SMT, MICROCONTROLLER, IC, FPGA")
    (attr smd)
    (fp_text reference "U15" (at -10.675 -14.7 180) (layer "F.SilkS")
        (effects (font (size 0.7 0.7) (thickness 0.15)) (justify left bottom))
    )
    (fp_text value "XC7K160T-FFG676" (at 0 15.5 180) (layer "F.Fab")
        (effects (font (size 0.7 0.7) (thickness 0.15)) (justify left bottom))
    )
    (pad "AC12" smd circle (at -1.5 9.499 180) (size 0.5 0.5) (layers "F.Cu" "F.Paste" "F.Mask")
      (net 354 "CK1_N") (pinfunction "IO_L15N_T2_DQS_33") (pintype "bidirectional") (die_length 18.956))
    (pad "AC13" smd circle (at -0.5 9.499 180) (size 0.5 0.5) (layers "F.Cu" "F.Paste" "F.Mask")
      (net 200 "A17") (pinfunction "IO_L17P_T2_33") (pintype "bidirectional") (die_length 21.425))
    (pad "AC14" smd circle (at 0.499 9.499 180) (size 0.5 0.5) (layers "F.Cu" "F.Paste" "F.Mask")
      (net 226 "DQ44") (pinfunction "IO_L8P_T1_32") (pintype "bidirectional") (die_length 15.875))
    (pad "AC15" smd circle (at 1.499 9.499 180) (size 0.5 0.5) (layers "F.Cu" "F.Paste" "F.Mask")
      (net 77 "VDDQ") (pinfunction "VCCO_32") (pintype "passive"))
    (pad "AC16" smd circle (at 2.499 9.499 180) (size 0.5 0.5) (layers "F.Cu" "F.Paste" "F.Mask")
      (net 224 "DQ42") (pinfunction "IO_L12N_T1_MRCC_32") (pintype "bidirectional") (die_length 17.396))
    (pad "AC17" smd circle (at 3.499 9.499 180) (size 0.5 0.5) (layers "F.Cu" "F.Paste" "F.Mask")
      (net 205 "DQ47") (pinfunction "IO_L14N_T2_SRCC_32") (pintype "bidirectional") (die_length 17.38))
    (pad "AC18" smd circle (at 4.499 9.499 180) (size 0.5 0.5) (layers "F.Cu" "F.Paste" "F.Mask")
      (net 334 "DQS5_P") (pinfunction "IO_L13P_T2_MRCC_32") (pintype "bidirectional") (die_length 20.008))
    (pad "AC19" smd circle (at 5.499 9.499 180) (size 0.5 0.5) (layers "F.Cu" "F.Paste" "F.Mask")
      (net 222 "DQ46") (pinfunction "IO_L17P_T2_32") (pintype "bidirectional") (die_length 22.343))
    (pad "AC20" smd circle (at 6.499 9.499 180) (size 0.5 0.5) (layers "F.Cu" "F.Paste" "F.Mask")
      (net 9 "GND") (pinfunction "GND") (pintype "passive"))
    (pad "AC21" smd circle (at 7.499 9.499 180) (size 0.5 0.5) (layers "F.Cu" "F.Paste" "F.Mask")
      (net 718 "unconnected-(U15A-IO_L18N_T2_12-PadAC21)") (pinfunction "IO_L18N_T2_12") (pintype "bidirectional+no_connect") (die_length 11.327))
    (pad "AC22" smd circle (at 8.499 9.499 180) (size 0.5 0.5) (layers "F.Cu" "F.Paste" "F.Mask")
      (net 719 "unconnected-(U15A-IO_L17N_T2_12-PadAC22)") (pinfunction "IO_L17N_T2_12") (pintype "bidirectional+no_connect") (die_length 12.08))
    (pad "AC23" smd circle (at 9.499 9.499 180) (size 0.5 0.5) (layers "F.Cu" "F.Paste" "F.Mask")
      (net 720 "unconnected-(U15A-IO_L14P_T2_SRCC_12-PadAC23)") (pinfunction "IO_L14P_T2_SRCC_12") (pintype "bidirectional+no_connect") (die_length 13.919))
    (pad "AC24" smd circle (at 10.499 9.499 180) (size 0.5 0.5) (layers "F.Cu" "F.Paste" "F.Mask")
      (net 154 "HR_RST") (pinfunction "IO_L14N_T2_SRCC_12") (pintype "bidirectional") (die_length 13.859))
    (pad "AC25" smd circle (at 11.499 9.499 180) (size 0.5 0.5) (layers "F.Cu" "F.Paste" "F.Mask")
      (net 143 "3V3_SYS") (pinfunction "VCCO_12") (pintype "passive"))
    (pad "AC26" smd circle (at 12.499 9.499 180) (size 0.5 0.5) (layers "F.Cu" "F.Paste" "F.Mask")
      (net 155 "HR_CS") (pinfunction "IO_L9N_T1_DQS_12") (pintype "bidirectional") (die_length 17.028))
    (pad "AD1" smd circle (at -12.5 10.499 180) (size 0.5 0.5) (layers "F.Cu" "F.Paste" "F.Mask")
      (net 277 "DQ23") (pinfunction "IO_L20P_T3_34") (pintype "bidirectional") (die_length 23.961))
    (pad "AD2" smd circle (at -11.5 10.499 180) (size 0.5 0.5) (layers "F.Cu" "F.Paste" "F.Mask")
      (net 77 "VDDQ") (pinfunction "VCCO_34") (pintype "passive"))
    (pad "AD3" smd circle (at -10.5 10.499 180) (size 0.5 0.5) (layers "F.Cu" "F.Paste" "F.Mask")
      (net 329 "DQS12_N") (pinfunction "IO_L19N_T3_VREF_34") (pintype "bidirectional") (die_length 21.156))
    (pad "AD4" smd circle (at -9.5 10.499 180) (size 0.5 0.5) (layers "F.Cu" "F.Paste" "F.Mask")
      (net 327 "DQS12_P") (pinfunction "IO_L19P_T3_34") (pintype "bidirectional") (die_length 21.197))
    (pad "AD5" smd circle (at -8.5 10.499 180) (size 0.5 0.5) (layers "F.Cu" "F.Paste" "F.Mask")
      (net 256 "DQ26") (pinfunction "IO_L18N_T2_34") (pintype "bidirectional") (die_length 19.989))
    (pad "AD6" smd circle (at -7.5 10.499 180) (size 0.5 0.5) (layers "F.Cu" "F.Paste" "F.Mask")
      (net 287 "DQ27") (pinfunction "IO_L18P_T2_34") (pintype "bidirectional") (die_length 20.498))
    (pad "AD7" smd circle (at -6.5 10.499 180) (size 0.5 0.5) (layers "F.Cu" "F.Paste" "F.Mask")
      (net 9 "GND") (pinfunction "GND") (pintype "passive"))
    (pad "AD8" smd circle (at -5.5 10.499 180) (size 0.5 0.5) (layers "F.Cu" "F.Paste" "F.Mask")
      (net 721 "unconnected-(U15G-IO_L9N_T1_DQS_33-PadAD8)") (pinfunction "IO_L9N_T1_DQS_33") (pintype "bidirectional+no_connect") (die_length 16.577))
    (pad "AD9" smd circle (at -4.5 10.499 180) (size 0.5 0.5) (layers "F.Cu" "F.Paste" "F.Mask")
      (net 276 "A5") (pinfunction "IO_L12N_T1_MRCC_33") (pintype "bidirectional") (die_length 17.579))
    (pad "AD10" smd circle (at -3.5 10.499 180) (size 0.5 0.5) (layers "F.Cu" "F.Paste" "F.Mask")
      (net 269 "A3") (pinfunction "IO_L20P_T3_33") (pintype "bidirectional") (die_length 16.019))
    (pad "AD11" smd circle (at -2.5 10.499 180) (size 0.5 0.5) (layers "F.Cu" "F.Paste" "F.Mask")
      (net 291 "A2") (pinfunction "IO_L19P_T3_33") (pintype "bidirectional") (die_length 18.739))
    (pad "AD12" smd circle (at -1.5 10.499 180) (size 0.5 0.5) (layers "F.Cu" "F.Paste" "F.Mask")
      (net 77 "VDDQ") (pinfunction "VCCO_33") (pintype "passive"))
    (pad "AD13" smd circle (at -0.5 10.499 180) (size 0.5 0.5) (layers "F.Cu" "F.Paste" "F.Mask")
      (net 207 "A13") (pinfunction "IO_L17N_T2_33") (pintype "bidirectional") (die_length 19.307))
    (pad "AD14" smd circle (at 0.499 10.499 180) (size 0.5 0.5) (layers "F.Cu" "F.Paste" "F.Mask")
      (net 212 "DQ37") (pinfunction "IO_L8N_T1_32") (pintype "bidirectional") (die_length 17.8))
    (pad "AD15" smd circle (at 1.499 10.499 180) (size 0.5 0.5) (layers "F.Cu" "F.Paste" "F.Mask")
      (net 331 "DQS13_P") (pinfunction "IO_L4P_T0_32") (pintype "bidirectional") (die_length 19.249))
    (pad "AD16" smd circle (at 2.499 10.499 180) (size 0.5 0.5) (layers "F.Cu" "F.Paste" "F.Mask")
      (net 203 "DQ45") (pinfunction "IO_L6P_T0_32") (pintype "bidirectional") (die_length 19.246))
    (pad "AD17" smd circle (at 3.499 10.499 180) (size 0.5 0.5) (layers "F.Cu" "F.Paste" "F.Mask")
      (net 9 "GND") (pinfunction "GND") (pintype "passive"))
    (pad "AD18" smd circle (at 4.499 10.499 180) (size 0.5 0.5) (layers "F.Cu" "F.Paste" "F.Mask")
      (net 336 "DQS5_N") (pinfunction "IO_L13N_T2_MRCC_32") (pintype "bidirectional") (die_length 20.423))
    (pad "AD19" smd circle (at 5.499 10.499 180) (size 0.5 0.5) (layers "F.Cu" "F.Paste" "F.Mask")
      (net 189 "DQ41") (pinfunction "IO_L17N_T2_32") (pintype "bidirectional") (die_length 20.752))
    (pad "AD20" smd circle (at 6.499 10.499 180) (size 0.5 0.5) (layers "F.Cu" "F.Paste" "F.Mask")
      (net 335 "DQS14_P") (pinfunction "IO_L15P_T2_DQS_32") (pintype "bidirectional") (die_length 22.214))
    (pad "AD21" smd circle (at 7.499 10.499 180) (size 0.5 0.5) (layers "F.Cu" "F.Paste" "F.Mask")
      (net 722 "unconnected-(U15A-IO_L19P_T3_12-PadAD21)") (pinfunction "IO_L19P_T3_12") (pintype "bidirectional+no_connect") (die_length 13.92))
    (pad "AD22" smd circle (at 8.499 10.499 180) (size 0.5 0.5) (layers "F.Cu" "F.Paste" "F.Mask")
      (net 143 "3V3_SYS") (pinfunction "VCCO_12") (pintype "passive"))
    (pad "AD23" smd circle (at 9.499 10.499 180) (size 0.5 0.5) (layers "F.Cu" "F.Paste" "F.Mask")
      (net 158 "HR_RW") (pinfunction "IO_L16P_T2_12") (pintype "bidirectional") (die_length 14.54))
    (pad "AD24" smd circle (at 10.499 10.499 180) (size 0.5 0.5) (layers "F.Cu" "F.Paste" "F.Mask")
      (net 162 "HR_DQ7") (pinfunction "IO_L16N_T2_12") (pintype "bidirectional") (die_length 14.673))
    (pad "AD25" smd circle (at 11.499 10.499 180) (size 0.5 0.5) (layers "F.Cu" "F.Paste" "F.Mask")
      (net 156 "HR_DQ1") (pinfunction "IO_L23P_T3_12") (pintype "bidirectional") (die_length 16.272))
    (pad "AD26" smd circle (at 12.499 10.499 180) (size 0.5 0.5) (layers "F.Cu" "F.Paste" "F.Mask")
      (net 164 "HR_CKP") (pinfunction "IO_L21P_T3_DQS_12") (pintype "bidirectional") (die_length 17.707))
    (pad "AE1" smd circle (at -12.5 11.499 180) (size 0.5 0.5) (layers "F.Cu" "F.Paste" "F.Mask")
      (net 286 "DQ19") (pinfunction "IO_L20N_T3_34") (pintype "bidirectional") (die_length 23.86))
    (pad "AE2" smd circle (at -11.5 11.499 180) (size 0.5 0.5) (layers "F.Cu" "F.Paste" "F.Mask")
      (net 252 "DQ28") (pinfunction "IO_L22N_T3_34") (pintype "bidirectional") (die_length 25.162))
    (pad "AE3" smd circle (at -10.5 11.499 180) (size 0.5 0.5) (layers "F.Cu" "F.Paste" "F.Mask")
      (net 254 "DQ24") (pinfunction "IO_L22P_T3_34") (pintype "bidirectional") (die_length 24.57))
    (pad "AE4" smd circle (at -9.5 11.499 180) (size 0.5 0.5) (layers "F.Cu" "F.Paste" "F.Mask")
      (net 9 "GND") (pinfunction "GND") (pintype "passive"))
    (pad "AE5" smd circle (at -8.5 11.499 180) (size 0.5 0.5) (layers "F.Cu" "F.Paste" "F.Mask")
      (net 255 "DQ30") (pinfunction "IO_L23N_T3_34") (pintype "bidirectional") (die_length 20.276))
    (pad "AE6" smd circle (at -7.5 11.499 180) (size 0.5 0.5) (layers "F.Cu" "F.Paste" "F.Mask")
      (net 279 "DQ31") (pinfunction "IO_L23P_T3_34") (pintype "bidirectional") (die_length 20.819))
    (pad "AE7" smd circle (at -6.5 11.499 180) (size 0.5 0.5) (layers "F.Cu" "F.Paste" "F.Mask")
      (net 266 "A9") (pinfunction "IO_L7P_T1_33") (pintype "bidirectional") (die_length 17.815))
    (pad "AE8" smd circle (at -5.5 11.499 180) (size 0.5 0.5) (layers "F.Cu" "F.Paste" "F.Mask")
      (net 268 "A8") (pinfunction "IO_L22P_T3_33") (pintype "bidirectional") (die_length 19.534))
    (pad "AE9" smd circle (at -4.5 11.499 180) (size 0.5 0.5) (layers "F.Cu" "F.Paste" "F.Mask")
      (net 77 "VDDQ") (pinfunction "VCCO_33") (pintype "passive"))
    (pad "AE10" smd circle (at -3.5 11.499 180) (size 0.5 0.5) (layers "F.Cu" "F.Paste" "F.Mask")
      (net 296 "~{ALERT}") (pinfunction "IO_L20N_T3_33") (pintype "bidirectional") (die_length 16.714))
    (pad "AE11" smd circle (at -2.5 11.499 180) (size 0.5 0.5) (layers "F.Cu" "F.Paste" "F.Mask")
      (net 312 "VREF_33") (pinfunction "IO_L19N_T3_VREF_33") (pintype "bidirectional") (die_length 17.525))
    (pad "AE12" smd circle (at -1.5 11.499 180) (size 0.5 0.5) (layers "F.Cu" "F.Paste" "F.Mask")
      (net 355 "CK0_P") (pinfunction "IO_L21P_T3_DQS_33") (pintype "bidirectional") (die_length 19.187))
    (pad "AE13" smd circle (at -0.5 11.499 180) (size 0.5 0.5) (layers "F.Cu" "F.Paste" "F.Mask")
      (net 199 "PARITY") (pinfunction "IO_L23P_T3_33") (pintype "bidirectional") (die_length 20.167))
    (pad "AE14" smd circle (at 0.499 11.499 180) (size 0.5 0.5) (layers "F.Cu" "F.Paste" "F.Mask")
      (net 9 "GND") (pinfunction "GND") (pintype "passive"))
    (pad "AE15" smd circle (at 1.499 11.499 180) (size 0.5 0.5) (layers "F.Cu" "F.Paste" "F.Mask")
      (net 333 "DQS13_N") (pinfunction "IO_L4N_T0_32") (pintype "bidirectional") (die_length 20.349))
    (pad "AE16" smd circle (at 2.499 11.499 180) (size 0.5 0.5) (layers "F.Cu" "F.Paste" "F.Mask")
      (net 194 "DQ33") (pinfunction "IO_L6N_T0_VREF_32") (pintype "bidirectional") (die_length 18.914))
    (pad "AE17" smd circle (at 3.499 11.499 180) (size 0.5 0.5) (layers "F.Cu" "F.Paste" "F.Mask")
      (net 330 "DQS4_P") (pinfunction "IO_L1P_T0_32") (pintype "bidirectional") (die_length 25.66))
    (pad "AE18" smd circle (at 4.499 11.499 180) (size 0.5 0.5) (layers "F.Cu" "F.Paste" "F.Mask")
      (net 202 "DQ39") (pinfunction "IO_L3P_T0_DQS_32") (pintype "bidirectional") (die_length 23.868))
    (pad "AE19" smd circle (at 5.499 11.499 180) (size 0.5 0.5) (layers "F.Cu" "F.Paste" "F.Mask")
      (net 77 "VDDQ") (pinfunction "VCCO_32") (pintype "passive"))
    (pad "AE20" smd circle (at 6.499 11.499 180) (size 0.5 0.5) (layers "F.Cu" "F.Paste" "F.Mask")
      (net 337 "DQS14_N") (pinfunction "IO_L15N_T2_DQS_32") (pintype "bidirectional") (die_length 21.92))
    (pad "AE21" smd circle (at 7.499 11.499 180) (size 0.5 0.5) (layers "F.Cu" "F.Paste" "F.Mask")
      (net 723 "unconnected-(U15A-IO_L19N_T3_VREF_12-PadAE21)") (pinfunction "IO_L19N_T3_VREF_12") (pintype "bidirectional+no_connect") (die_length 13.224))
    (pad "AE22" smd circle (at 8.499 11.499 180) (size 0.5 0.5) (layers "F.Cu" "F.Paste" "F.Mask")
      (net 165 "HR_DQ3") (pinfunction "IO_L24P_T3_12") (pintype "bidirectional") (die_length 13.617))
    (pad "AE23" smd circle (at 9.499 11.499 180) (size 0.5 0.5) (layers "F.Cu" "F.Paste" "F.Mask")
      (net 157 "HR_DQ0") (pinfunction "IO_L22P_T3_12") (pintype "bidirectional") (die_length 17.11))
    (pad "AE24" smd circle (at 10.499 11.499 180) (size 0.5 0.5) (layers "F.Cu" "F.Paste" "F.Mask")
      (net 9 "GND") (pinfunction "GND") (pintype "passive"))
    (pad "AE25" smd circle (at 11.499 11.499 180) (size 0.5 0.5) (layers "F.Cu" "F.Paste" "F.Mask")
      (net 163 "HR_DQ6") (pinfunction "IO_L23N_T3_12") (pintype "bidirectional") (die_length 16.458))
    (pad "AE26" smd circle (at 12.499 11.499 180) (size 0.5 0.5) (layers "F.Cu" "F.Paste" "F.Mask")
      (net 159 "HR_CKN") (pinfunction "IO_L21N_T3_DQS_12") (pintype "bidirectional") (die_length 17.907))
    (pad "AF1" smd circle (at -12.5 12.499 180) (size 0.5 0.5) (layers "F.Cu" "F.Paste" "F.Mask")
      (net 9 "GND") (pinfunction "GND") (pintype "passive"))
    (pad "AF2" smd circle (at -11.5 12.499 180) (size 0.5 0.5) (layers "F.Cu" "F.Paste" "F.Mask")
      (net 285 "DQ29") (pinfunction "IO_L24N_T3_34") (pintype "bidirectional") (die_length 24.825))
    (pad "AF3" smd circle (at -10.5 12.499 180) (size 0.5 0.5) (layers "F.Cu" "F.Paste" "F.Mask")
      (net 271 "DQ25") (pinfunction "IO_L24P_T3_34") (pintype "bidirectional") (die_length 23.875))
    (pad "AF4" smd circle (at -9.5 12.499 180) (size 0.5 0.5) (layers "F.Cu" "F.Paste" "F.Mask")
      (net 328 "DQS3_N") (pinfunction "IO_L21N_T3_DQS_34") (pintype "bidirectional") (die_length 21.687))
    (pad "AF5" smd circle (at -8.5 12.499 180) (size 0.5 0.5) (layers "F.Cu" "F.Paste" "F.Mask")
      (net 326 "DQS3_P") (pinfunction "IO_L21P_T3_DQS_34") (pintype "bidirectional") (die_length 22.107))
    (pad "AF6" smd circle (at -7.5 12.499 180) (size 0.5 0.5) (layers "F.Cu" "F.Paste" "F.Mask")
      (net 77 "VDDQ") (pinfunction "VCCO_34") (pintype "passive"))
    (pad "AF7" smd circle (at -6.5 12.499 180) (size 0.5 0.5) (layers "F.Cu" "F.Paste" "F.Mask")
      (net 284 "A7") (pinfunction "IO_L7N_T1_33") (pintype "bidirectional") (die_length 18.816))
    (pad "AF8" smd circle (at -5.5 12.499 180) (size 0.5 0.5) (layers "F.Cu" "F.Paste" "F.Mask")
      (net 262 "~{RESET}") (pinfunction "IO_L22N_T3_33") (pintype "bidirectional") (die_length 19.356))
    (pad "AF9" smd circle (at -4.5 12.499 180) (size 0.5 0.5) (layers "F.Cu" "F.Paste" "F.Mask")
      (net 280 "BG1") (pinfunction "IO_L24N_T3_33") (pintype "bidirectional") (die_length 18.041))
    (pad "AF10" smd circle (at -3.5 12.499 180) (size 0.5 0.5) (layers "F.Cu" "F.Paste" "F.Mask")
      (net 240 "A0") (pinfunction "IO_L24P_T3_33") (pintype "bidirectional") (die_length 18.552))
    (pad "AF11" smd circle (at -2.5 12.499 180) (size 0.5 0.5) (layers "F.Cu" "F.Paste" "F.Mask")
      (net 9 "GND") (pinfunction "GND") (pintype "passive"))
    (pad "AF12" smd circle (at -1.5 12.499 180) (size 0.5 0.5) (layers "F.Cu" "F.Paste" "F.Mask")
      (net 356 "CK0_N") (pinfunction "IO_L21N_T3_DQS_33") (pintype "bidirectional") (die_length 18.818))
    (pad "AF13" smd circle (at -0.5 12.499 180) (size 0.5 0.5) (layers "F.Cu" "F.Paste" "F.Mask")
      (net 236 "~{CAS}\\A15") (pinfunction "IO_L23N_T3_33") (pintype "bidirectional") (die_length 20.747))
    (pad "AF14" smd circle (at 0.499 12.499 180) (size 0.5 0.5) (layers "F.Cu" "F.Paste" "F.Mask")
      (net 233 "DQ36") (pinfunction "IO_L2P_T0_32") (pintype "bidirectional") (die_length 20.408))
    (pad "AF15" smd circle (at 1.499 12.499 180) (size 0.5 0.5) (layers "F.Cu" "F.Paste" "F.Mask")
      (net 232 "DQ32") (pinfunction "IO_L2N_T0_32") (pintype "bidirectional") (die_length 21.691))
    (pad "AF16" smd circle (at 2.499 12.499 180) (size 0.5 0.5) (layers "F.Cu" "F.Paste" "F.Mask")
      (net 77 "VDDQ") (pinfunction "VCCO_32") (pintype "passive"))
    (pad "AF17" smd circle (at 3.499 12.499 180) (size 0.5 0.5) (layers "F.Cu" "F.Paste" "F.Mask")
      (net 332 "DQS4_N") (pinfunction "IO_L1N_T0_32") (pintype "bidirectional") (die_length 25.392))
    (pad "AF18" smd circle (at 4.499 12.499 180) (size 0.5 0.5) (layers "F.Cu" "F.Paste" "F.Mask")
      (net 228 "DQ38") (pinfunction "IO_L3N_T0_DQS_32") (pintype "bidirectional") (die_length 23.477))
    (pad "AF19" smd circle (at 5.499 12.499 180) (size 0.5 0.5) (layers "F.Cu" "F.Paste" "F.Mask")
      (net 227 "DQ34") (pinfunction "IO_L5P_T0_32") (pintype "bidirectional") (die_length 22.609))
    (pad "AF20" smd circle (at 6.499 12.499 180) (size 0.5 0.5) (layers "F.Cu" "F.Paste" "F.Mask")
      (net 213 "DQ35") (pinfunction "IO_L5N_T0_32") (pintype "bidirectional") (die_length 22.255))
    (pad "AF21" smd circle (at 7.499 12.499 180) (size 0.5 0.5) (layers "F.Cu" "F.Paste" "F.Mask")
      (net 9 "GND") (pinfunction "GND") (pintype "passive"))
    (pad "AF22" smd circle (at 8.499 12.499 180) (size 0.5 0.5) (layers "F.Cu" "F.Paste" "F.Mask")
      (net 789 "DDR_PRESENCE") (pinfunction "IO_L24N_T3_12") (pintype "bidirectional") (die_length 14.462))
    (pad "AF23" smd circle (at 9.499 12.499 180) (size 0.5 0.5) (layers "F.Cu" "F.Paste" "F.Mask")
      (net 161 "HR_DQ4") (pinfunction "IO_L22N_T3_12") (pintype "bidirectional") (die_length 16.26))
  )
)
